# SCM (Grand Teton) — schematic netlist excerpt (pin names and nets, part order shuffled) for the footprints in the layout excerpt that follows; sources: Cadence DE-HDL packaged netlist, KiCad conversion of 12092022_DA0F0TMDCD0_F0T_Management_Board_D_brd_V3_OCP.brd

R319  Q_RES  4.7K 1% CHIP  pkg 0402LF  page 42 : A = P3V3_AUX ; B = BMC_ID_BEEP_SEL
R353  Q_RES  120 1% CHIP  pkg 0402LF  page 20 : A = M_BMC_DDR4_MA<2> ; B = P1V2_AUX

(kicad_pcb
	(version 20260206)
	(generator "pcbnew")
	(generator_version "10.0")
	(general
		(thickness 1.6)
		(legacy_teardrops no)
	)
	(paper "A4")
	(title_block
		(title "12092022_DA0F0TMDCD0_F0T_Management_Board_D_brd_V3_OCP.brd")
		(comment 1 "Grand Teton / footprints 270-272 of 1440")
	)
	(layers
		(0 "F.Cu" signal "TOP")
		(4 "In1.Cu" signal "GND")
		(6 "In2.Cu" signal "IN1")
		(8 "In3.Cu" signal "GND1")
		(10 "In4.Cu" signal "IN2")
		(12 "In5.Cu" signal "VCC")
		(14 "In6.Cu" signal "VCC1")
		(16 "In7.Cu" signal "IN3")
		(18 "In8.Cu" signal "GND2")
		(20 "In9.Cu" signal "IN4")
		(22 "In10.Cu" signal "GND3")
		(2 "B.Cu" signal "BOTTOM")
		(9 "F.Adhes" user "F.Adhesive")
		(11 "B.Adhes" user "B.Adhesive")
		(13 "F.Paste" user "Package Geometry/Pastemask Top")
		(15 "B.Paste" user "Package Geometry/Pastemask Bottom")
		(5 "F.SilkS" user "Ref Des/Silkscreen Top")
		(7 "B.SilkS" user "Ref Des/Silkscreen Bottom")
		(1 "F.Mask" user "Board Geometry/Soldermask Top")
		(3 "B.Mask" user "Board Geometry/Soldermask Bottom")
		(17 "Dwgs.User" user "User.Drawings")
		(19 "Cmts.User" user "User.Comments")
		(21 "Eco1.User" user "User.Eco1")
		(23 "Eco2.User" user "User.Eco2")
		(25 "Edge.Cuts" user "Board Geometry/Outline")
		(27 "Margin" user)
		(31 "F.CrtYd" user "Package Geometry/Place Bound Top")
		(29 "B.CrtYd" user "Package Geometry/Place Bound Bottom")
		(35 "F.Fab" user "Ref Des/Assembly Top")
		(33 "B.Fab" user "Ref Des/Assembly Bottom")
	)
	(footprint ""
		(layer "F.Cu")
		(at 47.879 -67.818 180)
		(property "Reference" "R319"
			(at 0 0 180)
			(layer "F.SilkS")
			(hide yes)
			(effects
				(font
					(size 1.27 1.27)
				)
			)
		)
		(property "Value" ""
			(at 0 0 180)
			(layer "F.Fab")
			(effects
				(font
					(size 1.27 1.27)
				)
			)
		)
		(duplicate_pad_numbers_are_jumpers no)
		(fp_line
			(start 0.7874 0.4064)
			(end -0.7874 0.4064)
			(stroke
				(width 0.1524)
				(type default)
			)
			(layer "F.SilkS")
		)
		(fp_line
			(start 0.7874 -0.4064)
			(end 0.7874 0.4064)
			(stroke
				(width 0.1524)
				(type default)
			)
			(layer "F.SilkS")
		)
		(fp_line
			(start -0.7874 0.4064)
			(end -0.7874 -0.4064)
			(stroke
				(width 0.1524)
				(type default)
			)
			(layer "F.SilkS")
		)
		(fp_line
			(start -0.7874 -0.4064)
			(end 0.7874 -0.4064)
			(stroke
				(width 0.1524)
				(type default)
			)
			(layer "F.SilkS")
		)
		(fp_line
			(start 0.67945 0.3048)
			(end 0.120396 0.3048)
			(stroke
				(width 0.1)
				(type default)
			)
			(layer "F.Fab")
		)
		(fp_line
			(start 0.67945 -0.3048)
			(end 0.67945 0.3048)
			(stroke
				(width 0.1)
				(type default)
			)
			(layer "F.Fab")
		)
		(fp_line
			(start 0.12065 -0.2794)
			(end 0.12065 -0.3048)
			(stroke
				(width 0.1)
				(type default)
			)
			(layer "F.Fab")
		)
		(fp_line
			(start 0.12065 -0.3048)
			(end 0.67945 -0.3048)
			(stroke
				(width 0.1)
				(type default)
			)
			(layer "F.Fab")
		)
		(fp_line
			(start 0.120396 0.3048)
			(end 0.120396 0.2794)
			(stroke
				(width 0.1)
				(type default)
			)
			(layer "F.Fab")
		)
		(fp_line
			(start 0.120396 0.2794)
			(end -0.12065 0.2794)
			(stroke
				(width 0.1)
				(type default)
			)
			(layer "F.Fab")
		)
		(fp_line
			(start -0.12065 0.3048)
			(end -0.67945 0.3048)
			(stroke
				(width 0.1)
				(type default)
			)
			(layer "F.Fab")
		)
		(fp_line
			(start -0.12065 0.2794)
			(end -0.12065 0.3048)
			(stroke
				(width 0.1)
				(type default)
			)
			(layer "F.Fab")
		)
		(fp_line
			(start -0.12065 -0.2794)
			(end 0.12065 -0.2794)
			(stroke
				(width 0.1)
				(type default)
			)
			(layer "F.Fab")
		)
		(fp_line
			(start -0.12065 -0.305054)
			(end -0.12065 -0.2794)
			(stroke
				(width 0.1)
				(type default)
			)
			(layer "F.Fab")
		)
		(fp_line
			(start -0.67945 0.3048)
			(end -0.67945 -0.305054)
			(stroke
				(width 0.1)
				(type default)
			)
			(layer "F.Fab")
		)
		(fp_line
			(start -0.67945 -0.305054)
			(end -0.12065 -0.305054)
			(stroke
				(width 0.1)
				(type default)
			)
			(layer "F.Fab")
		)
		(pad "1" smd circle
			(at -0.40005 0 180)
			(size 0 0)
			(layers "F.Cu" "F.Mask" "F.Paste")
			(net "P3V3_AUX")
		)
		(pad "2" smd circle
			(at 0.40005 0 180)
			(size 0 0)
			(layers "F.Cu" "F.Mask" "F.Paste")
			(net "BMC_ID_BEEP_SEL")
		)
	)
	(footprint ""
		(layer "F.Cu")
		(at 26.416 -40.0304)
		(property "Reference" ""
			(at 0 0 0)
			(layer "F.SilkS")
			(hide yes)
			(effects
				(font
					(size 1.27 1.27)
				)
			)
		)
		(property "Value" ""
			(at 0 0 0)
			(layer "F.Fab")
			(effects
				(font
					(size 1.27 1.27)
				)
			)
		)
		(duplicate_pad_numbers_are_jumpers no)
		(pad "1" smd circle
			(at 0 0)
			(size 0.9906 0.9906)
			(layers "F.Cu" "F.Mask" "F.Paste")
			(net "Net_326")
		)
		(zone
			(layer "F.Cu")
			(hatch none 0.5)
			(connect_pads
				(clearance 0)
			)
			(min_thickness 0.25)
			(keepout
				(tracks not_allowed)
				(vias allowed)
				(pads allowed)
				(copperpour not_allowed)
				(footprints allowed)
			)
			(placement
				(enabled no)
				(sheetname "")
			)
			(fill
				(thermal_gap 0.5)
				(thermal_bridge_width 0.5)
				(island_removal_mode 0)
			)
			(polygon
				(pts
					(arc
						(start 28.0416 -40.0304)
						(mid 24.7904 -40.0304)
						(end 28.0416 -40.0304)
					)
				)
			)
		)
	)
	(footprint ""
		(layer "F.Cu")
		(at 76.691744 -37.559488 -90)
		(property "Reference" "R353"
			(at 0 0 270)
			(layer "F.SilkS")
			(hide yes)
			(effects
				(font
					(size 1.27 1.27)
				)
			)
		)
		(property "Value" ""
			(at 0 0 270)
			(layer "F.Fab")
			(effects
				(font
					(size 1.27 1.27)
				)
			)
		)
		(duplicate_pad_numbers_are_jumpers no)
		(fp_line
			(start -0.7874 0.4064)
			(end -0.7874 -0.4064)
			(stroke
				(width 0.1524)
				(type default)
			)
			(layer "F.SilkS")
		)
		(fp_line
			(start 0.7874 0.4064)
			(end -0.7874 0.4064)
			(stroke
				(width 0.1524)
				(type default)
			)
			(layer "F.SilkS")
		)
		(fp_line
			(start -0.7874 -0.4064)
			(end 0.7874 -0.4064)
			(stroke
				(width 0.1524)
				(type default)
			)
			(layer "F.SilkS")
		)
		(fp_line
			(start 0.7874 -0.4064)
			(end 0.7874 0.4064)
			(stroke
				(width 0.1524)
				(type default)
			)
			(layer "F.SilkS")
		)
		(fp_line
			(start -0.67945 0.3048)
			(end -0.67945 -0.305054)
			(stroke
				(width 0.1)
				(type default)
			)
			(layer "F.Fab")
		)
		(fp_line
			(start -0.12065 0.3048)
			(end -0.67945 0.3048)
			(stroke
				(width 0.1)
				(type default)
			)
			(layer "F.Fab")
		)
		(fp_line
			(start 0.120396 0.3048)
			(end 0.120396 0.2794)
			(stroke
				(width 0.1)
				(type default)
			)
			(layer "F.Fab")
		)
		(fp_line
			(start 0.67945 0.3048)
			(end 0.120396 0.3048)
			(stroke
				(width 0.1)
				(type default)
			)
			(layer "F.Fab")
		)
		(fp_line
			(start -0.12065 0.2794)
			(end -0.12065 0.3048)
			(stroke
				(width 0.1)
				(type default)
			)
			(layer "F.Fab")
		)
		(fp_line
			(start 0.120396 0.2794)
			(end -0.12065 0.2794)
			(stroke
				(width 0.1)
				(type default)
			)
			(layer "F.Fab")
		)
		(fp_line
			(start -0.12065 -0.2794)
			(end 0.12065 -0.2794)
			(stroke
				(width 0.1)
				(type default)
			)
			(layer "F.Fab")
		)
		(fp_line
			(start 0.12065 -0.2794)
			(end 0.12065 -0.3048)
			(stroke
				(width 0.1)
				(type default)
			)
			(layer "F.Fab")
		)
		(fp_line
			(start 0.12065 -0.3048)
			(end 0.67945 -0.3048)
			(stroke
				(width 0.1)
				(type default)
			)
			(layer "F.Fab")
		)
		(fp_line
			(start 0.67945 -0.3048)
			(end 0.67945 0.3048)
			(stroke
				(width 0.1)
				(type default)
			)
			(layer "F.Fab")
		)
		(fp_line
			(start -0.67945 -0.305054)
			(end -0.12065 -0.305054)
			(stroke
				(width 0.1)
				(type default)
			)
			(layer "F.Fab")
		)
		(fp_line
			(start -0.12065 -0.305054)
			(end -0.12065 -0.2794)
			(stroke
				(width 0.1)
				(type default)
			)
			(layer "F.Fab")
		)
		(pad "1" smd circle
			(at -0.40005 0 270)
			(size 0 0)
			(layers "F.Cu" "F.Mask" "F.Paste")
			(net "M_BMC_DDR4_MA<2>")
		)
		(pad "2" smd circle
			(at 0.40005 0 270)
			(size 0 0)
			(layers "F.Cu" "F.Mask" "F.Paste")
			(net "P1V2_AUX")
		)
	)
)
